# SCM (Grand Teton) — schematic netlist excerpt (pin names and nets, part order shuffled) for the footprints in the layout excerpt that follows; sources: Cadence DE-HDL packaged netlist, KiCad conversion of 12092022_DA0F0TMDCD0_F0T_Management_Board_D_brd_V3_OCP.brd

R670  Q_RES  0 5% CHIP  pkg 0402LF  page 28 : A = DEBUG_PORT_PRSNT_BUF_R_EN ; B = DEBUG_PORT_PRSNT_BUF_EN
R193  Q_RES  100K 1% CHIP  pkg 0402LF  page 29 : A = P3V3_AUX ; B = SPA_SIN_SW_DBG

(kicad_pcb
	(version 20260206)
	(generator "pcbnew")
	(generator_version "10.0")
	(general
		(thickness 1.6)
		(legacy_teardrops no)
	)
	(paper "A4")
	(title_block
		(title "12092022_DA0F0TMDCD0_F0T_Management_Board_D_brd_V3_OCP.brd")
		(comment 1 "Grand Teton / footprints 1191-1192 of 1440")
	)
	(layers
		(0 "F.Cu" signal "TOP")
		(4 "In1.Cu" signal "GND")
		(6 "In2.Cu" signal "IN1")
		(8 "In3.Cu" signal "GND1")
		(10 "In4.Cu" signal "IN2")
		(12 "In5.Cu" signal "VCC")
		(14 "In6.Cu" signal "VCC1")
		(16 "In7.Cu" signal "IN3")
		(18 "In8.Cu" signal "GND2")
		(20 "In9.Cu" signal "IN4")
		(22 "In10.Cu" signal "GND3")
		(2 "B.Cu" signal "BOTTOM")
		(9 "F.Adhes" user "F.Adhesive")
		(11 "B.Adhes" user "B.Adhesive")
		(13 "F.Paste" user "Package Geometry/Pastemask Top")
		(15 "B.Paste" user "Package Geometry/Pastemask Bottom")
		(5 "F.SilkS" user "Ref Des/Silkscreen Top")
		(7 "B.SilkS" user "Ref Des/Silkscreen Bottom")
		(1 "F.Mask" user "Board Geometry/Soldermask Top")
		(3 "B.Mask" user "Board Geometry/Soldermask Bottom")
		(17 "Dwgs.User" user "User.Drawings")
		(19 "Cmts.User" user "User.Comments")
		(21 "Eco1.User" user "User.Eco1")
		(23 "Eco2.User" user "User.Eco2")
		(25 "Edge.Cuts" user "Board Geometry/Outline")
		(27 "Margin" user)
		(31 "F.CrtYd" user "Package Geometry/Place Bound Top")
		(29 "B.CrtYd" user "Package Geometry/Place Bound Bottom")
		(35 "F.Fab" user "Ref Des/Assembly Top")
		(33 "B.Fab" user "Ref Des/Assembly Bottom")
	)
	(footprint ""
		(layer "B.Cu")
		(at 47.10938 -24.1173 -90)
		(property "Reference" "R670"
			(at 0 0 90)
			(layer "B.SilkS")
			(hide yes)
			(effects
				(font
					(size 1.27 1.27)
				)
				(justify mirror)
			)
		)
		(property "Value" ""
			(at 0 0 90)
			(layer "B.Fab")
			(effects
				(font
					(size 1.27 1.27)
				)
				(justify mirror)
			)
		)
		(duplicate_pad_numbers_are_jumpers no)
		(fp_line
			(start -0.7874 0.4064)
			(end 0.7874 0.4064)
			(stroke
				(width 0.1524)
				(type default)
			)
			(layer "B.SilkS")
		)
		(fp_line
			(start 0.7874 0.4064)
			(end 0.7874 -0.4064)
			(stroke
				(width 0.1524)
				(type default)
			)
			(layer "B.SilkS")
		)
		(fp_line
			(start -0.7874 -0.4064)
			(end -0.7874 0.4064)
			(stroke
				(width 0.1524)
				(type default)
			)
			(layer "B.SilkS")
		)
		(fp_line
			(start 0.7874 -0.4064)
			(end -0.7874 -0.4064)
			(stroke
				(width 0.1524)
				(type default)
			)
			(layer "B.SilkS")
		)
		(fp_line
			(start -0.67945 0.3048)
			(end -0.120396 0.3048)
			(stroke
				(width 0.1)
				(type default)
			)
			(layer "B.Fab")
		)
		(fp_line
			(start -0.120396 0.3048)
			(end -0.120396 0.2794)
			(stroke
				(width 0.1)
				(type default)
			)
			(layer "B.Fab")
		)
		(fp_line
			(start 0.12065 0.3048)
			(end 0.67945 0.3048)
			(stroke
				(width 0.1)
				(type default)
			)
			(layer "B.Fab")
		)
		(fp_line
			(start 0.67945 0.3048)
			(end 0.67945 -0.305054)
			(stroke
				(width 0.1)
				(type default)
			)
			(layer "B.Fab")
		)
		(fp_line
			(start -0.120396 0.2794)
			(end 0.12065 0.2794)
			(stroke
				(width 0.1)
				(type default)
			)
			(layer "B.Fab")
		)
		(fp_line
			(start 0.12065 0.2794)
			(end 0.12065 0.3048)
			(stroke
				(width 0.1)
				(type default)
			)
			(layer "B.Fab")
		)
		(fp_line
			(start -0.12065 -0.2794)
			(end -0.12065 -0.3048)
			(stroke
				(width 0.1)
				(type default)
			)
			(layer "B.Fab")
		)
		(fp_line
			(start 0.12065 -0.2794)
			(end -0.12065 -0.2794)
			(stroke
				(width 0.1)
				(type default)
			)
			(layer "B.Fab")
		)
		(fp_line
			(start -0.67945 -0.3048)
			(end -0.67945 0.3048)
			(stroke
				(width 0.1)
				(type default)
			)
			(layer "B.Fab")
		)
		(fp_line
			(start -0.12065 -0.3048)
			(end -0.67945 -0.3048)
			(stroke
				(width 0.1)
				(type default)
			)
			(layer "B.Fab")
		)
		(fp_line
			(start 0.12065 -0.305054)
			(end 0.12065 -0.2794)
			(stroke
				(width 0.1)
				(type default)
			)
			(layer "B.Fab")
		)
		(fp_line
			(start 0.67945 -0.305054)
			(end 0.12065 -0.305054)
			(stroke
				(width 0.1)
				(type default)
			)
			(layer "B.Fab")
		)
		(pad "1" smd circle
			(at 0.40005 0 90)
			(size 0 0)
			(layers "B.Cu" "B.Mask" "B.Paste")
			(net "DEBUG_PORT_PRSNT_BUF_R_EN")
		)
		(pad "2" smd circle
			(at -0.40005 0 90)
			(size 0 0)
			(layers "B.Cu" "B.Mask" "B.Paste")
			(net "DEBUG_PORT_PRSNT_BUF_EN")
		)
	)
	(footprint ""
		(layer "B.Cu")
		(at 61.3918 -24.257 90)
		(property "Reference" "R193"
			(at 0 0 90)
			(layer "B.SilkS")
			(hide yes)
			(effects
				(font
					(size 1.27 1.27)
				)
				(justify mirror)
			)
		)
		(property "Value" ""
			(at 0 0 90)
			(layer "B.Fab")
			(effects
				(font
					(size 1.27 1.27)
				)
				(justify mirror)
			)
		)
		(duplicate_pad_numbers_are_jumpers no)
		(fp_line
			(start 0.7874 -0.4064)
			(end -0.7874 -0.4064)
			(stroke
				(width 0.1524)
				(type default)
			)
			(layer "B.SilkS")
		)
		(fp_line
			(start -0.7874 -0.4064)
			(end -0.7874 0.4064)
			(stroke
				(width 0.1524)
				(type default)
			)
			(layer "B.SilkS")
		)
		(fp_line
			(start 0.7874 0.4064)
			(end 0.7874 -0.4064)
			(stroke
				(width 0.1524)
				(type default)
			)
			(layer "B.SilkS")
		)
		(fp_line
			(start -0.7874 0.4064)
			(end 0.7874 0.4064)
			(stroke
				(width 0.1524)
				(type default)
			)
			(layer "B.SilkS")
		)
		(fp_line
			(start 0.67945 -0.305054)
			(end 0.12065 -0.305054)
			(stroke
				(width 0.1)
				(type default)
			)
			(layer "B.Fab")
		)
		(fp_line
			(start 0.12065 -0.305054)
			(end 0.12065 -0.2794)
			(stroke
				(width 0.1)
				(type default)
			)
			(layer "B.Fab")
		)
		(fp_line
			(start -0.12065 -0.3048)
			(end -0.67945 -0.3048)
			(stroke
				(width 0.1)
				(type default)
			)
			(layer "B.Fab")
		)
		(fp_line
			(start -0.67945 -0.3048)
			(end -0.67945 0.3048)
			(stroke
				(width 0.1)
				(type default)
			)
			(layer "B.Fab")
		)
		(fp_line
			(start 0.12065 -0.2794)
			(end -0.12065 -0.2794)
			(stroke
				(width 0.1)
				(type default)
			)
			(layer "B.Fab")
		)
		(fp_line
			(start -0.12065 -0.2794)
			(end -0.12065 -0.3048)
			(stroke
				(width 0.1)
				(type default)
			)
			(layer "B.Fab")
		)
		(fp_line
			(start 0.12065 0.2794)
			(end 0.12065 0.3048)
			(stroke
				(width 0.1)
				(type default)
			)
			(layer "B.Fab")
		)
		(fp_line
			(start -0.120396 0.2794)
			(end 0.12065 0.2794)
			(stroke
				(width 0.1)
				(type default)
			)
			(layer "B.Fab")
		)
		(fp_line
			(start 0.67945 0.3048)
			(end 0.67945 -0.305054)
			(stroke
				(width 0.1)
				(type default)
			)
			(layer "B.Fab")
		)
		(fp_line
			(start 0.12065 0.3048)
			(end 0.67945 0.3048)
			(stroke
				(width 0.1)
				(type default)
			)
			(layer "B.Fab")
		)
		(fp_line
			(start -0.120396 0.3048)
			(end -0.120396 0.2794)
			(stroke
				(width 0.1)
				(type default)
			)
			(layer "B.Fab")
		)
		(fp_line
			(start -0.67945 0.3048)
			(end -0.120396 0.3048)
			(stroke
				(width 0.1)
				(type default)
			)
			(layer "B.Fab")
		)
		(pad "1" smd circle
			(at 0.40005 0 270)
			(size 0 0)
			(layers "B.Cu" "B.Mask" "B.Paste")
			(net "P3V3_AUX")
		)
		(pad "2" smd circle
			(at -0.40005 0 270)
			(size 0 0)
			(layers "B.Cu" "B.Mask" "B.Paste")
			(net "SPA_SIN_SW_DBG")
		)
	)
)
